FILE_TYPE = CONNECTIVITY;
{Allegro Design Entry HDL 16.6-p007 (v16-6-112F) 10/10/2012}
"PAGE_NUMBER" = 84;
0"NC";
1"M_K_CLK_DN<3:0>";
2"M_K_DQ<63:0>";
3"M_K_CS_N<7:0>";
4"M_K_ECC<7:0>";
5"M_K_CKE<3:0>";
6"M_K_ODT<3:0>";
7"M_K_BA<1:0>";
8"M_K_MA<17:0>";
9"M_K_BG<1:0>";
10"M_K_CLK_DP<3:0>";
11"M_K_DQS_DP<17:0>";
12"M_K_DQS_DN<17:0>";
13"GND\g";
14"PVTT_KLM\g";
15"PVPP_KLM\g";
16"GND\g";
17"GND\g";
18"P12V_NVDIMM_KLM\g";
19"GND\g";
20"PVPP_KLM\g";
21"PVDDQ_KLM\g";
22"FM_DIMM_EVENT_COD_N";
23"M_K_DQS_DN<17>";
24"M_K_DQS_DN<16>";
25"M_K_DQS_DP<17>";
26"M_K_DQS_DP<16>";
27"M_K_DQS_DP<15>";
28"M_K_DQS_DN<15>";
29"M_K_DQS_DN<14>";
30"M_K_DQS_DN<13>";
31"M_K_DQS_DN<12>";
32"M_K_DQS_DN<11>";
33"M_K_DQS_DP<14>";
34"M_K_DQS_DP<13>";
35"M_K_DQS_DP<12>";
36"M_K_DQS_DP<11>";
37"M_K_DQS_DP<10>";
38"M_K_DQS_DN<9>";
39"M_K_DQS_DN<8>";
40"M_K_DQS_DN<7>";
41"M_K_DQS_DN<6>";
42"M_K_DQS_DN<10>";
43"M_K_DQS_DP<9>";
44"M_K_DQS_DP<8>";
45"M_K_DQS_DP<7>";
46"M_K_DQS_DP<6>";
47"M_K_DQS_DP<5>";
48"M_K_DQS_DN<5>";
49"M_K_DQS_DN<4>";
50"M_K_DQS_DN<3>";
51"M_K_DQS_DN<2>";
52"M_K_DQS_DN<1>";
53"M_K_DQS_DN<0>";
54"M_K_DQS_DP<4>";
55"M_K_DQS_DP<3>";
56"M_K_DQS_DP<2>";
57"M_K_DQS_DP<1>";
58"M_K_DQS_DP<0>";
59"M_K_DQ<62>";
60"M_K_DQ<60>";
61"M_K_DQ<58>";
62"M_K_DQ<57>";
63"M_K_DQ<56>";
64"M_K_DQ<59>";
65"M_K_DQ<61>";
66"M_K_DQ<63>";
67"M_K_MA<13>";
68"M_K_MA<16>";
69"M_K_MA<15>";
70"M_K_MA<14>";
71"M_K_MA<11>";
72"M_K_MA<10>";
73"M_K_MA<17>";
74"M_K_MA<12>";
75"M_K_DQ<47>";
76"M_K_DQ<48>";
77"M_K_DQ<49>";
78"M_K_DQ<50>";
79"M_K_DQ<51>";
80"M_K_DQ<52>";
81"M_K_DQ<53>";
82"M_K_DQ<54>";
83"M_K_DQ<46>";
84"M_K_DQ<55>";
85"M_K_DQ<41>";
86"M_K_DQ<40>";
87"M_K_DQ<35>";
88"M_K_DQ<38>";
89"M_K_DQ<36>";
90"M_K_DQ<37>";
91"M_K_DQ<39>";
92"M_K_DQ<42>";
93"M_K_DQ<43>";
94"M_K_DQ<44>";
95"M_K_DQ<45>";
96"M_K_DQ<26>";
97"M_K_DQ<27>";
98"M_K_DQ<25>";
99"M_K_DQ<30>";
100"M_K_DQ<31>";
101"M_K_DQ<32>";
102"M_K_DQ<33>";
103"M_K_DQ<34>";
104"M_K_DQ<28>";
105"M_K_DQ<29>";
106"M_K_DQ<17>";
107"M_K_DQ<15>";
108"M_K_DQ<16>";
109"M_K_DQ<18>";
110"M_K_DQ<19>";
111"M_K_DQ<20>";
112"M_K_DQ<21>";
113"M_K_DQ<22>";
114"M_K_DQ<23>";
115"M_K_DQ<24>";
116"M_K_CLK_DP<2>";
117"M_K_CLK_DP<3>";
118"M_K_BG<0>";
119"M_K_BG<1>";
120"M_K_MA<2>";
121"M_K_BA<0>";
122"M_K_MA<9>";
123"M_K_MA<8>";
124"M_K_MA<7>";
125"M_K_MA<6>";
126"M_K_MA<5>";
127"M_K_MA<4>";
128"M_K_MA<3>";
129"M_K_MA<1>";
130"M_K_MA<0>";
131"M_K_BA<1>";
132"M_K_C<2>";
133"M_K_ECC<6>";
134"M_K_CS_N<4>";
135"M_K_CKE<2>";
136"M_K_ODT<3>";
137"M_K_ODT<2>";
138"M_K_ECC<7>";
139"M_K_CKE<3>";
140"M_K_ECC<0>";
141"M_K_ECC<1>";
142"M_K_ECC<2>";
143"M_K_ECC<3>";
144"M_K_ECC<4>";
145"M_K_ECC<5>";
146"M_K_CS_N<5>";
147"M_K_CS_N<6>";
148"M_K_CS_N<7>";
149"M_KLM_RST_N";
150"M_K_PAR";
151"M_K_DQ<9>";
152"M_K_DQ<5>";
153"M_K_DQ<6>";
154"M_K_DQ<7>";
155"M_K_DQ<8>";
156"M_K_DQ<10>";
157"M_K_DQ<11>";
158"M_K_DQ<12>";
159"M_K_DQ<13>";
160"M_K_DQ<14>";
161"M_K_DQ<0>";
162"M_K_DQ<4>";
163"M_K_DQ<3>";
164"M_K_DQ<2>";
165"M_K_DQ<1>";
166"M_K_ACT_N";
167"M_K_ALERT_N";
168"SMB_DDR_KLM_VPP_SDA";
169"SMB_DDR_KLM_VPP_SCL";
170"FM_ADR_COMPLETE_KLM_N";
171"M_K_CLK_DN<2>";
172"M_K_CLK_DN<3>";
173"TP_CH_K_DIMM0_RFU_1";
174"TP_CH_K_DIMM0_RFU_0";
175"TP_CH_K_DIMM0_RFU_2";
176"M_K_VREF";
%"GND"
"1","(-3500,1475)","2","mstr_symbols","I1";
;
HDL_POWER"GND"
ROOM"DDR4_CH_C"
BODY_TYPE"PLUMBING"
BOM_COST"MEM"
CDS_LIB"mstr_symbols"
SIZE"1B"
VOLTAGE"0";
"A\NAC"13;
%"PVTT_KLM"
"1","(600,2425)","0","mstr_symbols","I100";
;
HDL_POWER"PVTT_KLM"
ROOM"DDR4_CH_C"
BODY_TYPE"PLUMBING"
CDS_LIB"mstr_symbols"
BOM_COST"MEM"
VOLTAGE"0.6V";
"G\NAC"14;
%"PVPP_KLM"
"1","(750,2725)","0","mstr_symbols","I101";
;
HDL_POWER"PVPP_KLM"
ROOM"DDR4_CH_C"
BODY_TYPE"PLUMBING"
CDS_LIB"mstr_symbols"
BOM_COST"MEM"
VOLTAGE"2.5V";
"G\NAC"15;
%"SCONN288_H44441003"
"2","(1600,3975)","0","mstr_sconn","I102";
;
CDS_SEC"2"
ROOM"DDR4_CH_K"
CDS_LOCATION"J9M1"
SEC"2"
SEC_TYPE"PIP"
CDS_LIB"mstr_sconn"
BOM_COST"MEM"
PACK_TYPE"PIP"
MATERIAL"SCONN"
PART_NUMBER"H44441-003"
LOCATION"J9M1";
"DQS0N"
$PN"152"53;
"DQS0P"
$PN"153"58;
"DQS10N"
$PN"19"42;
"DQS10P"
$PN"18"37;
"DQS11N"
$PN"30"32;
"DQS11P"
$PN"29"36;
"DQS12N"
$PN"41"31;
"DQS12P"
$PN"40"35;
"DQS13N"
$PN"100"30;
"DQS13P"
$PN"99"34;
"DQS14N"
$PN"111"29;
"DQS14P"
$PN"110"33;
"DQS15N"
$PN"122"28;
"DQS15P"
$PN"121"27;
"DQS16N"
$PN"133"24;
"DQS16P"
$PN"132"26;
"DQS17N"
$PN"52"23;
"DQS17P"
$PN"51"25;
"DQS1N"
$PN"163"52;
"DQS1P"
$PN"164"57;
"DQS2N"
$PN"174"51;
"DQS2P"
$PN"175"56;
"DQS3N"
$PN"185"50;
"DQS3P"
$PN"186"55;
"DQS4N"
$PN"244"49;
"DQS4P"
$PN"245"54;
"DQS5N"
$PN"255"48;
"DQS5P"
$PN"256"47;
"DQS6N"
$PN"266"41;
"DQS6P"
$PN"267"46;
"DQS7N"
$PN"277"40;
"DQS7P"
$PN"278"45;
"DQS8N"
$PN"196"39;
"DQS8P"
$PN"197"44;
"DQS9N"
$PN"8"38;
"DQS9P"
$PN"7"43;
%"TAP"
"6","(-1600,3775)","0","mstr_standard","I104";
;
HDL_TAP"TRUE"
BODY_TYPE"PLUMBING"
CDS_LIB"mstr_standard";
"B \NAC \NWC"8;
"S \NAC"
BN"3"128;
%"TAP"
"6","(-1600,3725)","0","mstr_standard","I105";
;
HDL_TAP"TRUE"
BODY_TYPE"PLUMBING"
CDS_LIB"mstr_standard";
"B \NAC \NWC"8;
"S \NAC"
BN"2"120;
%"TAP"
"6","(-1600,3925)","0","mstr_standard","I106";
;
HDL_TAP"TRUE"
BODY_TYPE"PLUMBING"
CDS_LIB"mstr_standard";
"B \NAC \NWC"8;
"S \NAC"
BN"6"125;
%"TAP"
"6","(-1600,3875)","0","mstr_standard","I107";
;
HDL_TAP"TRUE"
BODY_TYPE"PLUMBING"
CDS_LIB"mstr_standard";
"B \NAC \NWC"8;
"S \NAC"
BN"5"126;
%"TAP"
"6","(-1600,3825)","0","mstr_standard","I108";
;
HDL_TAP"TRUE"
BODY_TYPE"PLUMBING"
CDS_LIB"mstr_standard";
"B \NAC \NWC"8;
"S \NAC"
BN"4"127;
%"TAP"
"6","(-1600,3975)","0","mstr_standard","I109";
;
HDL_TAP"TRUE"
BODY_TYPE"PLUMBING"
CDS_LIB"mstr_standard";
"B \NAC \NWC"8;
"S \NAC"
BN"7"124;
%"TAP"
"6","(-1600,4025)","0","mstr_standard","I110";
;
HDL_TAP"TRUE"
BODY_TYPE"PLUMBING"
CDS_LIB"mstr_standard";
"B \NAC \NWC"8;
"S \NAC"
BN"8"123;
%"TAP"
"6","(-1600,4075)","0","mstr_standard","I111";
;
HDL_TAP"TRUE"
BODY_TYPE"PLUMBING"
CDS_LIB"mstr_standard";
"B \NAC \NWC"8;
"S \NAC"
BN"9"122;
%"TAP"
"6","(-1600,4175)","0","mstr_standard","I112";
;
HDL_TAP"TRUE"
BODY_TYPE"PLUMBING"
CDS_LIB"mstr_standard";
"B \NAC \NWC"8;
"S \NAC"
BN"11"71;
%"TAP"
"6","(-1600,4125)","0","mstr_standard","I113";
;
HDL_TAP"TRUE"
BODY_TYPE"PLUMBING"
CDS_LIB"mstr_standard";
"B \NAC \NWC"8;
"S \NAC"
BN"10"72;
%"TAP"
"6","(-1600,4225)","0","mstr_standard","I114";
;
HDL_TAP"TRUE"
BODY_TYPE"PLUMBING"
CDS_LIB"mstr_standard";
"B \NAC \NWC"8;
"S \NAC"
BN"12"74;
%"TAP"
"6","(-1600,4275)","0","mstr_standard","I115";
;
HDL_TAP"TRUE"
BODY_TYPE"PLUMBING"
CDS_LIB"mstr_standard";
"B \NAC \NWC"8;
"S \NAC"
BN"13"67;
%"TAP"
"6","(-1600,4325)","0","mstr_standard","I116";
;
HDL_TAP"TRUE"
BODY_TYPE"PLUMBING"
CDS_LIB"mstr_standard";
"B \NAC \NWC"8;
"S \NAC"
BN"14"70;
%"TAP"
"6","(-1600,4425)","0","mstr_standard","I117";
;
HDL_TAP"TRUE"
BODY_TYPE"PLUMBING"
CDS_LIB"mstr_standard";
"B \NAC \NWC"8;
"S \NAC"
BN"16"68;
%"TAP"
"6","(-1600,4375)","0","mstr_standard","I118";
;
HDL_TAP"TRUE"
BODY_TYPE"PLUMBING"
CDS_LIB"mstr_standard";
"B \NAC \NWC"8;
"S \NAC"
BN"15"69;
%"TAP"
"6","(-1600,4475)","0","mstr_standard","I119";
;
HDL_TAP"TRUE"
BODY_TYPE"PLUMBING"
CDS_LIB"mstr_standard";
"B \NAC \NWC"8;
"S \NAC"
BN"17"73;
%"TAP"
"6","(-100,3825)","2","mstr_standard","I120";
;
HDL_TAP"TRUE"
BODY_TYPE"PLUMBING"
CDS_LIB"mstr_standard";
"B \NAC \NWC"2;
"S \NAC"
BN"50"78;
%"TAP"
"6","(-100,3725)","2","mstr_standard","I121";
;
HDL_TAP"TRUE"
BODY_TYPE"PLUMBING"
CDS_LIB"mstr_standard";
"B \NAC \NWC"2;
"S \NAC"
BN"48"76;
%"TAP"
"6","(-100,3775)","2","mstr_standard","I122";
;
HDL_TAP"TRUE"
BODY_TYPE"PLUMBING"
CDS_LIB"mstr_standard";
"B \NAC \NWC"2;
"S \NAC"
BN"49"77;
%"TAP"
"6","(-100,3975)","2","mstr_standard","I123";
;
HDL_TAP"TRUE"
BODY_TYPE"PLUMBING"
CDS_LIB"mstr_standard";
"B \NAC \NWC"2;
"S \NAC"
BN"53"81;
%"TAP"
"6","(-100,3925)","2","mstr_standard","I124";
;
HDL_TAP"TRUE"
BODY_TYPE"PLUMBING"
CDS_LIB"mstr_standard";
"B \NAC \NWC"2;
"S \NAC"
BN"52"80;
%"TAP"
"6","(-100,3875)","2","mstr_standard","I125";
;
HDL_TAP"TRUE"
BODY_TYPE"PLUMBING"
CDS_LIB"mstr_standard";
"B \NAC \NWC"2;
"S \NAC"
BN"51"79;
%"TAP"
"6","(-100,4075)","2","mstr_standard","I126";
;
HDL_TAP"TRUE"
BODY_TYPE"PLUMBING"
CDS_LIB"mstr_standard";
"B \NAC \NWC"2;
"S \NAC"
BN"55"84;
%"TAP"
"6","(-100,4025)","2","mstr_standard","I127";
;
HDL_TAP"TRUE"
BODY_TYPE"PLUMBING"
CDS_LIB"mstr_standard";
"B \NAC \NWC"2;
"S \NAC"
BN"54"82;
%"TAP"
"6","(-100,4175)","2","mstr_standard","I128";
;
HDL_TAP"TRUE"
BODY_TYPE"PLUMBING"
CDS_LIB"mstr_standard";
"B \NAC \NWC"2;
"S \NAC"
BN"57"62;
%"TAP"
"6","(-100,4225)","2","mstr_standard","I129";
;
HDL_TAP"TRUE"
BODY_TYPE"PLUMBING"
CDS_LIB"mstr_standard";
"B \NAC \NWC"2;
"S \NAC"
BN"58"61;
%"TAP"
"6","(-100,4125)","2","mstr_standard","I130";
;
HDL_TAP"TRUE"
BODY_TYPE"PLUMBING"
CDS_LIB"mstr_standard";
"B \NAC \NWC"2;
"S \NAC"
BN"56"63;
%"TAP"
"6","(-100,4275)","2","mstr_standard","I131";
;
HDL_TAP"TRUE"
BODY_TYPE"PLUMBING"
CDS_LIB"mstr_standard";
"B \NAC \NWC"2;
"S \NAC"
BN"59"64;
%"TAP"
"6","(-100,4325)","2","mstr_standard","I132";
;
HDL_TAP"TRUE"
BODY_TYPE"PLUMBING"
CDS_LIB"mstr_standard";
"B \NAC \NWC"2;
"S \NAC"
BN"60"60;
%"TAP"
"6","(-100,4475)","2","mstr_standard","I133";
;
HDL_TAP"TRUE"
BODY_TYPE"PLUMBING"
CDS_LIB"mstr_standard";
"B \NAC \NWC"2;
"S \NAC"
BN"63"66;
%"TAP"
"6","(-100,4425)","2","mstr_standard","I134";
;
HDL_TAP"TRUE"
BODY_TYPE"PLUMBING"
CDS_LIB"mstr_standard";
"B \NAC \NWC"2;
"S \NAC"
BN"62"59;
%"TAP"
"6","(-100,4375)","2","mstr_standard","I135";
;
HDL_TAP"TRUE"
BODY_TYPE"PLUMBING"
CDS_LIB"mstr_standard";
"B \NAC \NWC"2;
"S \NAC"
BN"61"65;
%"GND"
"1","(2700,725)","2","mstr_symbols","I137";
;
HDL_POWER"GND"
ROOM"DDR4_CH_C"
BODY_TYPE"PLUMBING"
BOM_COST"MEM"
SIZE"1B"
CDS_LIB"mstr_symbols"
VOLTAGE"0";
"A\NAC"16;
%"SCONN288_H44441003"
"3","(3400,2025)","0","mstr_sconn","I138";
;
CDS_SEC"3"
ROOM"DDR4_CH_K"
CDS_LOCATION"J9M1"
SEC"3"
SEC_TYPE"PIP"
CDS_LIB"mstr_sconn"
BOM_COST"MEM"
PACK_TYPE"PIP"
MATERIAL"SCONN"
PART_NUMBER"H44441-003"
LOCATION"J9M1";
"VSS<46>"
$PN"147"17;
"VSS<45>"
$PN"149"17;
"VSS<87>"
$PN"15"16;
"VSS<86>"
$PN"17"16;
"VSS<85>"
$PN"20"16;
"VSS<84>"
$PN"22"16;
"VSS<83>"
$PN"24"16;
"VSS<82>"
$PN"26"16;
"VSS<81>"
$PN"28"16;
"VSS<80>"
$PN"31"16;
"VSS<79>"
$PN"33"16;
"VSS<78>"
$PN"35"16;
"VSS<77>"
$PN"37"16;
"VSS<76>"
$PN"39"16;
"VSS<75>"
$PN"42"16;
"VSS<74>"
$PN"44"16;
"VSS<73>"
$PN"46"16;
"VSS<72>"
$PN"48"16;
"VSS<71>"
$PN"50"16;
"VSS<70>"
$PN"53"16;
"VSS<69>"
$PN"55"16;
"VSS<68>"
$PN"57"16;
"VSS<67>"
$PN"94"16;
"VSS<66>"
$PN"96"16;
"VSS<65>"
$PN"98"16;
"VSS<64>"
$PN"101"16;
"VSS<63>"
$PN"103"16;
"VSS<62>"
$PN"105"16;
"VSS<61>"
$PN"107"16;
"VSS<60>"
$PN"109"16;
"VSS<59>"
$PN"112"16;
"VSS<58>"
$PN"114"16;
"VSS<57>"
$PN"116"16;
"VSS<56>"
$PN"118"16;
"VSS<55>"
$PN"120"16;
"VSS<54>"
$PN"123"16;
"VSS<53>"
$PN"125"16;
"VSS<52>"
$PN"127"16;
"VSS<51>"
$PN"129"16;
"VSS<50>"
$PN"131"16;
"VSS<49>"
$PN"134"16;
"VSS<48>"
$PN"136"16;
"VSS<47>"
$PN"138"16;
"VSS<44>"
$PN"151"17;
"VSS<43>"
$PN"154"17;
"VSS<42>"
$PN"156"17;
"VSS<41>"
$PN"158"17;
"VSS<40>"
$PN"160"17;
"VSS<39>"
$PN"162"17;
"VSS<38>"
$PN"165"17;
"VSS<37>"
$PN"167"17;
"VSS<36>"
$PN"169"17;
"VSS<35>"
$PN"171"17;
"VSS<34>"
$PN"173"17;
"VSS<33>"
$PN"176"17;
"VSS<32>"
$PN"178"17;
"VSS<31>"
$PN"180"17;
"VSS<30>"
$PN"182"17;
"VSS<29>"
$PN"184"17;
"VSS<28>"
$PN"187"17;
"VSS<27>"
$PN"189"17;
"VSS<26>"
$PN"191"17;
"VSS<25>"
$PN"193"17;
"VSS<24>"
$PN"195"17;
"VSS<23>"
$PN"198"17;
"VSS<22>"
$PN"200"17;
"VSS<21>"
$PN"202"17;
"VSS<20>"
$PN"239"17;
"VSS<19>"
$PN"241"17;
"VSS<18>"
$PN"243"17;
"VSS<17>"
$PN"246"17;
"VSS<16>"
$PN"248"17;
"VSS<15>"
$PN"250"17;
"VSS<14>"
$PN"252"17;
"VSS<13>"
$PN"254"17;
"VSS<12>"
$PN"257"17;
"VSS<11>"
$PN"259"17;
"VSS<10>"
$PN"261"17;
"VSS<9>"
$PN"263"17;
"VSS<8>"
$PN"265"17;
"VSS<7>"
$PN"268"17;
"VSS<6>"
$PN"270"17;
"VSS<5>"
$PN"272"17;
"VSS<4>"
$PN"274"17;
"VSS<3>"
$PN"276"17;
"VSS<2>"
$PN"279"17;
"VSS<1>"
$PN"281"17;
"VSS<0>"
$PN"283"17;
"VSS<88>"
$PN"13"16;
"VSS<89>"
$PN"11"16;
"VSS<90>"
$PN"9"16;
"VSS<91>"
$PN"6"16;
"VSS<92>"
$PN"4"16;
"VSS<93>"
$PN"2"16;
%"SCONN288_H44441003"
"1","(-850,2825)","0","mstr_sconn","I14";
;
CDS_SEC"1"
ROOM"DDR4_CH_K"
CDS_LOCATION"J9M1"
SEC"1"
SEC_TYPE"PIP"
CDS_LIB"mstr_sconn"
BOM_COST"MEM"
PACK_TYPE"PIP"
MATERIAL"SCONN"
PART_NUMBER"H44441-003"
LOCATION"J9M1";
"DQ<63>"
$PN"280"66;
"BA<1>"
$PN"224"131;
"CK1N"
$PN"219"172;
"CK0P"
$PN"74"116;
"S3_N_C<1>"
$PN"237"148;
"S2_N_C<0>"
$PN"93"147;
"S1_N"
$PN"89"146;
"DQ<29>"
$PN"181"105;
"DQ<28>"
$PN"36"104;
"C<2>"
$PN"235"132;
"A0"
$PN"79"130;
"A1"
$PN"72"129;
"A12"
$PN"65"74;
"A13"
$PN"232"67;
"A17"
$PN"234"73;
"A3"
$PN"71"128;
"A4"
$PN"214"127;
"A5"
$PN"213"126;
"A6"
$PN"69"125;
"A7"
$PN"211"124;
"A8"
$PN"68"123;
"A9"
$PN"66"122;
"CB<6>"
$PN"54"133;
"CB<5>"
$PN"192"145;
"CB<4>"
$PN"47"144;
"CB<3>"
$PN"201"143;
"CB<2>"
$PN"56"142;
"CB<1>"
$PN"194"141;
"CB<0>"
$PN"49"140;
"CK0N"
$PN"75"171;
"CKE<1>"
$PN"203"139;
"DQ<62>"
$PN"135"59;
"DQ<61>"
$PN"273"65;
"DQ<60>"
$PN"128"60;
"DQ<59>"
$PN"282"64;
"DQ<56>"
$PN"130"63;
"DQ<55>"
$PN"269"84;
"DQ<46>"
$PN"113"83;
"DQ<45>"
$PN"251"95;
"DQ<44>"
$PN"106"94;
"DQ<43>"
$PN"260"93;
"DQ<42>"
$PN"115"92;
"DQ<41>"
$PN"253"85;
"DQ<40>"
$PN"108"86;
"DQ<39>"
$PN"247"91;
"DQ<37>"
$PN"240"90;
"DQ<34>"
$PN"104"103;
"DQ<33>"
$PN"242"102;
"DQ<32>"
$PN"97"101;
"DQ<31>"
$PN"188"100;
"DQ<30>"
$PN"43"99;
"DQ<25>"
$PN"183"98;
"DQ<24>"
$PN"38"115;
"DQ<23>"
$PN"177"114;
"DQ<22>"
$PN"32"113;
"DQ<21>"
$PN"170"112;
"DQ<20>"
$PN"25"111;
"DQ<19>"
$PN"179"110;
"DQ<18>"
$PN"34"109;
"DQ<16>"
$PN"27"108;
"DQ<14>"
$PN"21"160;
"DQ<13>"
$PN"159"159;
"DQ<12>"
$PN"14"158;
"DQ<11>"
$PN"168"157;
"DQ<10>"
$PN"23"156;
"DQ<9>"
$PN"161"151;
"DQ<8>"
$PN"16"155;
"DQ<7>"
$PN"155"154;
"DQ<6>"
$PN"10"153;
"EVENT_N"
$PN"78"22;
"PAR"
$PN"222"150;
"RESET_N"
$PN"58"149;
"RFU<2>"
$PN"144"175;
"SCL"
$PN"141"169;
"SDA"
$PN"285"168;
"VREFCA"
$PN"146"176;
"CK1P"
$PN"218"117;
"BG<0>"
$PN"63"118;
"BG<1>"
$PN"207"119;
"BA<0>"
$PN"81"121;
"SA<0>"
$PN"139"20;
"VDDSPD"
$PN"284"20;
"SA<2>"
$PN"238"13;
"SA<1>"
$PN"140"13;
"DQ<1>"
$PN"150"165;
"DQ<0>"
$PN"5"161;
"ACT_N"
$PN"62"166;
"ALERT_N"
$PN"208"167;
"A2"
$PN"216"120;
"DQ<35>"
$PN"249"87;
"DQ<36>"
$PN"95"89;
"DQ<38>"
$PN"102"88;
"A10"
$PN"225"72;
"A11"
$PN"210"71;
"A14_WE_N"
$PN"228"70;
"A15_CAS_N"
$PN"86"69;
"A16_RAS_N"
$PN"82"68;
"CB<7>"
$PN"199"138;
"ODT<0>"
$PN"87"137;
"ODT<1>"
$PN"91"136;
"CKE<0>"
$PN"60"135;
"S0_N"
$PN"84"134;
"DQ<27>"
$PN"190"97;
"DQ<26>"
$PN"45"96;
"DQ<15>"
$PN"166"107;
"DQ<17>"
$PN"172"106;
"RFU<0>"
$PN"205"174;
"RFU<1>"
$PN"227"173;
"SAVE_N_NC"
$PN"230"170;
"DQ<57>"
$PN"275"62;
"DQ<58>"
$PN"137"61;
"DQ<54>"
$PN"124"82;
"DQ<53>"
$PN"262"81;
"DQ<52>"
$PN"117"80;
"DQ<51>"
$PN"271"79;
"DQ<50>"
$PN"126"78;
"DQ<49>"
$PN"264"77;
"DQ<48>"
$PN"119"76;
"DQ<47>"
$PN"258"75;
"DQ<2>"
$PN"12"164;
"DQ<3>"
$PN"157"163;
"DQ<4>"
$PN"3"162;
"DQ<5>"
$PN"148"152;
%"TAP"
"6","(2300,3125)","2","mstr_standard","I142";
;
HDL_TAP"TRUE"
BODY_TYPE"PLUMBING"
CDS_LIB"mstr_standard";
"B \NAC \NWC"11;
"S \NAC"
BN"0"58;
%"TAP"
"6","(2500,3075)","2","mstr_standard","I143";
;
HDL_TAP"TRUE"
BODY_TYPE"PLUMBING"
CDS_LIB"mstr_standard";
"B \NAC \NWC"12;
"S \NAC"
BN"0"53;
%"TAP"
"6","(2500,3175)","2","mstr_standard","I144";
;
HDL_TAP"TRUE"
BODY_TYPE"PLUMBING"
CDS_LIB"mstr_standard";
"B \NAC \NWC"12;
"S \NAC"
BN"1"52;
%"TAP"
"6","(2300,3325)","2","mstr_standard","I145";
;
HDL_TAP"TRUE"
BODY_TYPE"PLUMBING"
CDS_LIB"mstr_standard";
"B \NAC \NWC"11;
"S \NAC"
BN"2"56;
%"TAP"
"6","(2300,3225)","2","mstr_standard","I146";
;
HDL_TAP"TRUE"
BODY_TYPE"PLUMBING"
CDS_LIB"mstr_standard";
"B \NAC \NWC"11;
"S \NAC"
BN"1"57;
%"TAP"
"6","(2300,3425)","2","mstr_standard","I147";
;
HDL_TAP"TRUE"
BODY_TYPE"PLUMBING"
CDS_LIB"mstr_standard";
"B \NAC \NWC"11;
"S \NAC"
BN"3"55;
%"TAP"
"6","(2300,3525)","2","mstr_standard","I148";
;
HDL_TAP"TRUE"
BODY_TYPE"PLUMBING"
CDS_LIB"mstr_standard";
"B \NAC \NWC"11;
"S \NAC"
BN"4"54;
%"TAP"
"6","(2300,3625)","2","mstr_standard","I149";
;
HDL_TAP"TRUE"
BODY_TYPE"PLUMBING"
CDS_LIB"mstr_standard";
"B \NAC \NWC"11;
"S \NAC"
BN"5"47;
%"TAP"
"6","(2500,3275)","2","mstr_standard","I150";
;
HDL_TAP"TRUE"
BODY_TYPE"PLUMBING"
CDS_LIB"mstr_standard";
"B \NAC \NWC"12;
"S \NAC"
BN"2"51;
%"TAP"
"6","(2500,3375)","2","mstr_standard","I151";
;
HDL_TAP"TRUE"
BODY_TYPE"PLUMBING"
CDS_LIB"mstr_standard";
"B \NAC \NWC"12;
"S \NAC"
BN"3"50;
%"TAP"
"6","(2500,3675)","2","mstr_standard","I152";
;
HDL_TAP"TRUE"
BODY_TYPE"PLUMBING"
CDS_LIB"mstr_standard";
"B \NAC \NWC"12;
"S \NAC"
BN"6"41;
%"TAP"
"6","(2500,3575)","2","mstr_standard","I153";
;
HDL_TAP"TRUE"
BODY_TYPE"PLUMBING"
CDS_LIB"mstr_standard";
"B \NAC \NWC"12;
"S \NAC"
BN"5"48;
%"TAP"
"6","(2500,3475)","2","mstr_standard","I154";
;
HDL_TAP"TRUE"
BODY_TYPE"PLUMBING"
CDS_LIB"mstr_standard";
"B \NAC \NWC"12;
"S \NAC"
BN"4"49;
%"GND"
"1","(4100,725)","2","mstr_symbols","I155";
;
HDL_POWER"GND"
ROOM"DDR4_CH_C"
BODY_TYPE"PLUMBING"
BOM_COST"MEM"
SIZE"1B"
CDS_LIB"mstr_symbols"
VOLTAGE"0";
"A\NAC"17;
%"TAP"
"6","(2300,3725)","2","mstr_standard","I156";
;
HDL_TAP"TRUE"
BODY_TYPE"PLUMBING"
CDS_LIB"mstr_standard";
"B \NAC \NWC"11;
"S \NAC"
BN"6"46;
%"TAP"
"6","(2300,3825)","2","mstr_standard","I157";
;
HDL_TAP"TRUE"
BODY_TYPE"PLUMBING"
CDS_LIB"mstr_standard";
"B \NAC \NWC"11;
"S \NAC"
BN"7"45;
%"TAP"
"6","(2300,3925)","2","mstr_standard","I158";
;
HDL_TAP"TRUE"
BODY_TYPE"PLUMBING"
CDS_LIB"mstr_standard";
"B \NAC \NWC"11;
"S \NAC"
BN"8"44;
%"TAP"
"6","(2300,4025)","2","mstr_standard","I159";
;
HDL_TAP"TRUE"
BODY_TYPE"PLUMBING"
CDS_LIB"mstr_standard";
"B \NAC \NWC"11;
"S \NAC"
BN"9"43;
%"TAP"
"6","(2300,4225)","2","mstr_standard","I160";
;
HDL_TAP"TRUE"
BODY_TYPE"PLUMBING"
CDS_LIB"mstr_standard";
"B \NAC \NWC"11;
"S \NAC"
BN"11"36;
%"TAP"
"6","(2300,4125)","2","mstr_standard","I161";
;
HDL_TAP"TRUE"
BODY_TYPE"PLUMBING"
CDS_LIB"mstr_standard";
"B \NAC \NWC"11;
"S \NAC"
BN"10"37;
%"TAP"
"6","(2500,3975)","2","mstr_standard","I162";
;
HDL_TAP"TRUE"
BODY_TYPE"PLUMBING"
CDS_LIB"mstr_standard";
"B \NAC \NWC"12;
"S \NAC"
BN"9"38;
%"TAP"
"6","(2500,3775)","2","mstr_standard","I163";
;
HDL_TAP"TRUE"
BODY_TYPE"PLUMBING"
CDS_LIB"mstr_standard";
"B \NAC \NWC"12;
"S \NAC"
BN"7"40;
%"TAP"
"6","(2500,3875)","2","mstr_standard","I164";
;
HDL_TAP"TRUE"
BODY_TYPE"PLUMBING"
CDS_LIB"mstr_standard";
"B \NAC \NWC"12;
"S \NAC"
BN"8"39;
%"TAP"
"6","(2500,4175)","2","mstr_standard","I165";
;
HDL_TAP"TRUE"
BODY_TYPE"PLUMBING"
CDS_LIB"mstr_standard";
"B \NAC \NWC"12;
"S \NAC"
BN"11"32;
%"TAP"
"6","(2500,4075)","2","mstr_standard","I166";
;
HDL_TAP"TRUE"
BODY_TYPE"PLUMBING"
CDS_LIB"mstr_standard";
"B \NAC \NWC"12;
"S \NAC"
BN"10"42;
%"TAP"
"6","(2300,4325)","2","mstr_standard","I167";
;
HDL_TAP"TRUE"
BODY_TYPE"PLUMBING"
CDS_LIB"mstr_standard";
"B \NAC \NWC"11;
"S \NAC"
BN"12"35;
%"TAP"
"6","(2300,4425)","2","mstr_standard","I168";
;
HDL_TAP"TRUE"
BODY_TYPE"PLUMBING"
CDS_LIB"mstr_standard";
"B \NAC \NWC"11;
"S \NAC"
BN"13"34;
%"TAP"
"6","(2300,4525)","2","mstr_standard","I169";
;
HDL_TAP"TRUE"
BODY_TYPE"PLUMBING"
CDS_LIB"mstr_standard";
"B \NAC \NWC"11;
"S \NAC"
BN"14"33;
%"TAP"
"6","(2300,4625)","2","mstr_standard","I170";
;
HDL_TAP"TRUE"
BODY_TYPE"PLUMBING"
CDS_LIB"mstr_standard";
"B \NAC \NWC"11;
"S \NAC"
BN"15"27;
%"TAP"
"6","(2300,4725)","2","mstr_standard","I171";
;
HDL_TAP"TRUE"
BODY_TYPE"PLUMBING"
CDS_LIB"mstr_standard";
"B \NAC \NWC"11;
"S \NAC"
BN"16"26;
%"TAP"
"6","(2500,4475)","2","mstr_standard","I172";
;
HDL_TAP"TRUE"
BODY_TYPE"PLUMBING"
CDS_LIB"mstr_standard";
"B \NAC \NWC"12;
"S \NAC"
BN"14"29;
%"TAP"
"6","(2500,4275)","2","mstr_standard","I173";
;
HDL_TAP"TRUE"
BODY_TYPE"PLUMBING"
CDS_LIB"mstr_standard";
"B \NAC \NWC"12;
"S \NAC"
BN"12"31;
%"TAP"
"6","(2500,4375)","2","mstr_standard","I174";
;
HDL_TAP"TRUE"
BODY_TYPE"PLUMBING"
CDS_LIB"mstr_standard";
"B \NAC \NWC"12;
"S \NAC"
BN"13"30;
%"TAP"
"6","(2500,4675)","2","mstr_standard","I175";
;
HDL_TAP"TRUE"
BODY_TYPE"PLUMBING"
CDS_LIB"mstr_standard";
"B \NAC \NWC"12;
"S \NAC"
BN"16"24;
%"TAP"
"6","(2500,4575)","2","mstr_standard","I176";
;
HDL_TAP"TRUE"
BODY_TYPE"PLUMBING"
CDS_LIB"mstr_standard";
"B \NAC \NWC"12;
"S \NAC"
BN"15"28;
%"TAP"
"6","(2300,4825)","2","mstr_standard","I177";
;
HDL_TAP"TRUE"
BODY_TYPE"PLUMBING"
CDS_LIB"mstr_standard";
"B \NAC \NWC"11;
"S \NAC"
BN"17"25;
%"TAP"
"6","(2500,4775)","2","mstr_standard","I178";
;
HDL_TAP"TRUE"
BODY_TYPE"PLUMBING"
CDS_LIB"mstr_standard";
"B \NAC \NWC"12;
"S \NAC"
BN"17"23;
%"P12V_NVDIMM_KLM"
"1","(2150,2800)","0","mstr_symbols","I181";
;
HDL_POWER"P12V_NVDIMM_KLM"
BODY_TYPE"PLUMBING"
CDS_LIB"mstr_symbols"
VOLTAGE"12.0";
"G\NAC"18;
%"TAP"
"6","(-1600,2125)","0","mstr_standard","I19";
;
HDL_TAP"TRUE"
BODY_TYPE"PLUMBING"
CDS_LIB"mstr_standard";
"B \NAC \NWC"4;
"S \NAC"
BN"1"141;
%"TAP"
"6","(-1600,2075)","0","mstr_standard","I20";
;
HDL_TAP"TRUE"
BODY_TYPE"PLUMBING"
CDS_LIB"mstr_standard";
"B \NAC \NWC"4;
"S \NAC"
BN"0"140;
%"TAP"
"6","(-1600,2175)","0","mstr_standard","I21";
;
HDL_TAP"TRUE"
BODY_TYPE"PLUMBING"
CDS_LIB"mstr_standard";
"B \NAC \NWC"4;
"S \NAC"
BN"2"142;
%"TAP"
"6","(-1600,2225)","0","mstr_standard","I22";
;
HDL_TAP"TRUE"
BODY_TYPE"PLUMBING"
CDS_LIB"mstr_standard";
"B \NAC \NWC"4;
"S \NAC"
BN"3"143;
%"TAP"
"6","(-1600,2275)","0","mstr_standard","I23";
;
HDL_TAP"TRUE"
BODY_TYPE"PLUMBING"
CDS_LIB"mstr_standard";
"B \NAC \NWC"4;
"S \NAC"
BN"4"144;
%"TAP"
"6","(-1600,2375)","0","mstr_standard","I24";
;
HDL_TAP"TRUE"
BODY_TYPE"PLUMBING"
CDS_LIB"mstr_standard";
"B \NAC \NWC"4;
"S \NAC"
BN"6"133;
%"TAP"
"6","(-1600,2325)","0","mstr_standard","I25";
;
HDL_TAP"TRUE"
BODY_TYPE"PLUMBING"
CDS_LIB"mstr_standard";
"B \NAC \NWC"4;
"S \NAC"
BN"5"145;
%"TAP"
"6","(-1600,2425)","0","mstr_standard","I26";
;
HDL_TAP"TRUE"
BODY_TYPE"PLUMBING"
CDS_LIB"mstr_standard";
"B \NAC \NWC"4;
"S \NAC"
BN"7"138;
%"TAP"
"6","(-1600,2525)","0","mstr_standard","I27";
;
HDL_TAP"TRUE"
BODY_TYPE"PLUMBING"
CDS_LIB"mstr_standard";
"B \NAC \NWC"6;
"S \NAC"
BN"2"137;
%"TAP"
"6","(-1600,2575)","0","mstr_standard","I28";
;
HDL_TAP"TRUE"
BODY_TYPE"PLUMBING"
CDS_LIB"mstr_standard";
"B \NAC \NWC"6;
"S \NAC"
BN"3"136;
%"TAP"
"6","(-1600,2675)","0","mstr_standard","I29";
;
HDL_TAP"TRUE"
BODY_TYPE"PLUMBING"
CDS_LIB"mstr_standard";
"B \NAC \NWC"5;
"S \NAC"
BN"2"135;
%"GND"
"1","(-3000,875)","0","mstr_symbols","I3";
;
HDL_POWER"GND"
ROOM"DDR4_CH_C"
BODY_TYPE"PLUMBING"
BOM_COST"MEM"
SIZE"1B"
CDS_LIB"mstr_symbols"
VOLTAGE"0";
"A\NAC"19;
%"TAP"
"6","(-2100,3125)","0","mstr_standard","I33";
;
HDL_TAP"TRUE"
BODY_TYPE"PLUMBING"
CDS_LIB"mstr_standard";
"B \NAC \NWC"1;
"S \NAC"
BN"2"171;
%"TAP"
"6","(-1950,3175)","0","mstr_standard","I34";
;
HDL_TAP"TRUE"
BODY_TYPE"PLUMBING"
CDS_LIB"mstr_standard";
"B \NAC \NWC"10;
"S \NAC"
BN"2"116;
%"TAP"
"6","(-2100,3225)","0","mstr_standard","I37";
;
HDL_TAP"TRUE"
BODY_TYPE"PLUMBING"
CDS_LIB"mstr_standard";
"B \NAC \NWC"1;
"S \NAC"
BN"3"172;
%"TAP"
"6","(-1950,3275)","0","mstr_standard","I38";
;
HDL_TAP"TRUE"
BODY_TYPE"PLUMBING"
CDS_LIB"mstr_standard";
"B \NAC \NWC"10;
"S \NAC"
BN"3"117;
%"TAP"
"6","(-1600,2725)","0","mstr_standard","I39";
;
HDL_TAP"TRUE"
BODY_TYPE"PLUMBING"
CDS_LIB"mstr_standard";
"B \NAC \NWC"5;
"S \NAC"
BN"3"139;
%"CAP_A"
"1","(-3000,1125)","2","dev_discrete","I4";
;
ROOM"DDR4_CH_C"
$SEC"1"
CDS_SEC"1"
CDS_LIB"dev_discrete"
BOM_COST"MEM"
CDS_LOCATION"C9M1"
MATERIAL"X7R"
VOLTAGE"25V"
PACK_TYPE"0402V"
TOLERANCE"10%"
VALUE"0.01UF"
PART_NUMBER"A36096-045"
LOCATION"C9M1";
"B"
$PN"2"19;
"A"
$PN"1"176;
%"TAP"
"6","(-1600,2925)","0","mstr_standard","I40";
;
HDL_TAP"TRUE"
BODY_TYPE"PLUMBING"
CDS_LIB"mstr_standard";
"B \NAC \NWC"3;
"S \NAC"
BN"6"147;
%"TAP"
"6","(-1600,2875)","0","mstr_standard","I41";
;
HDL_TAP"TRUE"
BODY_TYPE"PLUMBING"
CDS_LIB"mstr_standard";
"B \NAC \NWC"3;
"S \NAC"
BN"5"146;
%"TAP"
"6","(-1600,2825)","0","mstr_standard","I42";
;
HDL_TAP"TRUE"
BODY_TYPE"PLUMBING"
CDS_LIB"mstr_standard";
"B \NAC \NWC"3;
"S \NAC"
BN"4"134;
%"TAP"
"6","(-1600,2975)","0","mstr_standard","I43";
;
HDL_TAP"TRUE"
BODY_TYPE"PLUMBING"
CDS_LIB"mstr_standard";
"B \NAC \NWC"3;
"S \NAC"
BN"7"148;
%"TAP"
"6","(-1600,3425)","0","mstr_standard","I44";
;
HDL_TAP"TRUE"
BODY_TYPE"PLUMBING"
CDS_LIB"mstr_standard";
"B \NAC \NWC"9;
"S \NAC"
BN"1"119;
%"TAP"
"6","(-1600,3375)","0","mstr_standard","I45";
;
HDL_TAP"TRUE"
BODY_TYPE"PLUMBING"
CDS_LIB"mstr_standard";
"B \NAC \NWC"9;
"S \NAC"
BN"0"118;
%"TAP"
"6","(-1600,3675)","0","mstr_standard","I46";
;
HDL_TAP"TRUE"
BODY_TYPE"PLUMBING"
CDS_LIB"mstr_standard";
"B \NAC \NWC"8;
"S \NAC"
BN"1"129;
%"TAP"
"6","(-1600,3625)","0","mstr_standard","I47";
;
HDL_TAP"TRUE"
BODY_TYPE"PLUMBING"
CDS_LIB"mstr_standard";
"B \NAC \NWC"8;
"S \NAC"
BN"0"130;
%"TAP"
"6","(-1600,3475)","0","mstr_standard","I48";
;
HDL_TAP"TRUE"
BODY_TYPE"PLUMBING"
CDS_LIB"mstr_standard";
"B \NAC \NWC"7;
"S \NAC"
BN"0"121;
%"TAP"
"6","(-1600,3525)","0","mstr_standard","I49";
;
HDL_TAP"TRUE"
BODY_TYPE"PLUMBING"
CDS_LIB"mstr_standard";
"B \NAC \NWC"7;
"S \NAC"
BN"1"131;
%"PVPP_KLM"
"1","(-3500,1825)","0","mstr_symbols","I5";
;
HDL_POWER"PVPP_KLM"
ROOM"DDR4_CH_C"
BODY_TYPE"PLUMBING"
CDS_LIB"mstr_symbols"
BOM_COST"MEM"
VOLTAGE"2.5V";
"G\NAC"20;
%"TAP"
"6","(-100,1325)","2","mstr_standard","I50";
;
HDL_TAP"TRUE"
BODY_TYPE"PLUMBING"
CDS_LIB"mstr_standard";
"B \NAC \NWC"2;
"S \NAC"
BN"0"161;
%"TAP"
"6","(-100,1375)","2","mstr_standard","I51";
;
HDL_TAP"TRUE"
BODY_TYPE"PLUMBING"
CDS_LIB"mstr_standard";
"B \NAC \NWC"2;
"S \NAC"
BN"1"165;
%"TAP"
"6","(-100,1425)","2","mstr_standard","I52";
;
HDL_TAP"TRUE"
BODY_TYPE"PLUMBING"
CDS_LIB"mstr_standard";
"B \NAC \NWC"2;
"S \NAC"
BN"2"164;
%"TAP"
"6","(-100,1475)","2","mstr_standard","I53";
;
HDL_TAP"TRUE"
BODY_TYPE"PLUMBING"
CDS_LIB"mstr_standard";
"B \NAC \NWC"2;
"S \NAC"
BN"3"163;
%"TAP"
"6","(-100,1525)","2","mstr_standard","I54";
;
HDL_TAP"TRUE"
BODY_TYPE"PLUMBING"
CDS_LIB"mstr_standard";
"B \NAC \NWC"2;
"S \NAC"
BN"4"162;
%"TAP"
"6","(-100,1625)","2","mstr_standard","I55";
;
HDL_TAP"TRUE"
BODY_TYPE"PLUMBING"
CDS_LIB"mstr_standard";
"B \NAC \NWC"2;
"S \NAC"
BN"6"153;
%"TAP"
"6","(-100,1575)","2","mstr_standard","I56";
;
HDL_TAP"TRUE"
BODY_TYPE"PLUMBING"
CDS_LIB"mstr_standard";
"B \NAC \NWC"2;
"S \NAC"
BN"5"152;
%"SCONN288_H44441003"
"4","(1450,1725)","0","mstr_sconn","I57";
;
CDS_SEC"4"
ROOM"DDR4_CH_K"
CDS_LOCATION"J9M1"
SEC"4"
SEC_TYPE"PIP"
CDS_LIB"mstr_sconn"
BOM_COST"MEM"
PACK_TYPE"PIP"
MATERIAL"SCONN"
PART_NUMBER"H44441-003"
LOCATION"J9M1";
"VDD<0>"
$PN"236"21;
"VDD<6>"
$PN"220"21;
"VDD<10>"
$PN"209"21;
"VDD<13>"
$PN"92"21;
"VDD<16>"
$PN"85"21;
"VDD<19>"
$PN"76"21;
"VDD<23>"
$PN"64"21;
"VDD<25>"
$PN"59"21;
"VTT<0>"
$PN"221"14;
"12V<1>"
$PN"1"18;
"12V<0>"
$PN"145"18;
"VDD<24>"
$PN"61"21;
"VDD<22>"
$PN"67"21;
"VDD<21>"
$PN"70"21;
"VDD<20>"
$PN"73"21;
"VDD<18>"
$PN"80"21;
"VDD<17>"
$PN"83"21;
"VDD<15>"
$PN"88"21;
"VDD<14>"
$PN"90"21;
"VDD<12>"
$PN"204"21;
"VDD<11>"
$PN"206"21;
"VDD<9>"
$PN"212"21;
"VDD<8>"
$PN"215"21;
"VDD<7>"
$PN"217"21;
"VDD<5>"
$PN"223"21;
"VDD<4>"
$PN"226"21;
"VDD<3>"
$PN"229"21;
"VDD<2>"
$PN"231"21;
"VDD<1>"
$PN"233"21;
"VPP<4>"
$PN"142"15;
"VPP<3>"
$PN"143"15;
"VPP<2>"
$PN"288"15;
"VPP<1>"
$PN"286"15;
"VPP<0>"
$PN"287"15;
"VTT<1>"
$PN"77"14;
%"TAP"
"6","(-100,1775)","2","mstr_standard","I58";
;
HDL_TAP"TRUE"
BODY_TYPE"PLUMBING"
CDS_LIB"mstr_standard";
"B \NAC \NWC"2;
"S \NAC"
BN"9"151;
%"TAP"
"6","(-100,1675)","2","mstr_standard","I59";
;
HDL_TAP"TRUE"
BODY_TYPE"PLUMBING"
CDS_LIB"mstr_standard";
"B \NAC \NWC"2;
"S \NAC"
BN"7"154;
%"TAP"
"6","(-100,1725)","2","mstr_standard","I60";
;
HDL_TAP"TRUE"
BODY_TYPE"PLUMBING"
CDS_LIB"mstr_standard";
"B \NAC \NWC"2;
"S \NAC"
BN"8"155;
%"TAP"
"6","(-100,1875)","2","mstr_standard","I61";
;
HDL_TAP"TRUE"
BODY_TYPE"PLUMBING"
CDS_LIB"mstr_standard";
"B \NAC \NWC"2;
"S \NAC"
BN"11"157;
%"TAP"
"6","(-100,1925)","2","mstr_standard","I62";
;
HDL_TAP"TRUE"
BODY_TYPE"PLUMBING"
CDS_LIB"mstr_standard";
"B \NAC \NWC"2;
"S \NAC"
BN"12"158;
%"TAP"
"6","(-100,1825)","2","mstr_standard","I63";
;
HDL_TAP"TRUE"
BODY_TYPE"PLUMBING"
CDS_LIB"mstr_standard";
"B \NAC \NWC"2;
"S \NAC"
BN"10"156;
%"TAP"
"6","(-100,2025)","2","mstr_standard","I64";
;
HDL_TAP"TRUE"
BODY_TYPE"PLUMBING"
CDS_LIB"mstr_standard";
"B \NAC \NWC"2;
"S \NAC"
BN"14"160;
%"TAP"
"6","(-100,1975)","2","mstr_standard","I65";
;
HDL_TAP"TRUE"
BODY_TYPE"PLUMBING"
CDS_LIB"mstr_standard";
"B \NAC \NWC"2;
"S \NAC"
BN"13"159;
%"TAP"
"6","(-100,2125)","2","mstr_standard","I66";
;
HDL_TAP"TRUE"
BODY_TYPE"PLUMBING"
CDS_LIB"mstr_standard";
"B \NAC \NWC"2;
"S \NAC"
BN"16"108;
%"TAP"
"6","(-100,2175)","2","mstr_standard","I67";
;
HDL_TAP"TRUE"
BODY_TYPE"PLUMBING"
CDS_LIB"mstr_standard";
"B \NAC \NWC"2;
"S \NAC"
BN"17"106;
%"TAP"
"6","(-100,2075)","2","mstr_standard","I68";
;
HDL_TAP"TRUE"
BODY_TYPE"PLUMBING"
CDS_LIB"mstr_standard";
"B \NAC \NWC"2;
"S \NAC"
BN"15"107;
%"TAP"
"6","(-100,2275)","2","mstr_standard","I69";
;
HDL_TAP"TRUE"
BODY_TYPE"PLUMBING"
CDS_LIB"mstr_standard";
"B \NAC \NWC"2;
"S \NAC"
BN"19"110;
%"TAP"
"6","(-100,2225)","2","mstr_standard","I70";
;
HDL_TAP"TRUE"
BODY_TYPE"PLUMBING"
CDS_LIB"mstr_standard";
"B \NAC \NWC"2;
"S \NAC"
BN"18"109;
%"TAP"
"6","(-100,2425)","2","mstr_standard","I71";
;
HDL_TAP"TRUE"
BODY_TYPE"PLUMBING"
CDS_LIB"mstr_standard";
"B \NAC \NWC"2;
"S \NAC"
BN"22"113;
%"TAP"
"6","(-100,2375)","2","mstr_standard","I72";
;
HDL_TAP"TRUE"
BODY_TYPE"PLUMBING"
CDS_LIB"mstr_standard";
"B \NAC \NWC"2;
"S \NAC"
BN"21"112;
%"TAP"
"6","(-100,2325)","2","mstr_standard","I73";
;
HDL_TAP"TRUE"
BODY_TYPE"PLUMBING"
CDS_LIB"mstr_standard";
"B \NAC \NWC"2;
"S \NAC"
BN"20"111;
%"TAP"
"6","(-100,2475)","2","mstr_standard","I74";
;
HDL_TAP"TRUE"
BODY_TYPE"PLUMBING"
CDS_LIB"mstr_standard";
"B \NAC \NWC"2;
"S \NAC"
BN"23"114;
%"TAP"
"6","(-100,2525)","2","mstr_standard","I75";
;
HDL_TAP"TRUE"
BODY_TYPE"PLUMBING"
CDS_LIB"mstr_standard";
"B \NAC \NWC"2;
"S \NAC"
BN"24"115;
%"TAP"
"6","(-100,2675)","2","mstr_standard","I76";
;
HDL_TAP"TRUE"
BODY_TYPE"PLUMBING"
CDS_LIB"mstr_standard";
"B \NAC \NWC"2;
"S \NAC"
BN"27"97;
%"TAP"
"6","(-100,2625)","2","mstr_standard","I77";
;
HDL_TAP"TRUE"
BODY_TYPE"PLUMBING"
CDS_LIB"mstr_standard";
"B \NAC \NWC"2;
"S \NAC"
BN"26"96;
%"TAP"
"6","(-100,2575)","2","mstr_standard","I78";
;
HDL_TAP"TRUE"
BODY_TYPE"PLUMBING"
CDS_LIB"mstr_standard";
"B \NAC \NWC"2;
"S \NAC"
BN"25"98;
%"PVDDQ_KLM"
"1","(325,2275)","0","mstr_symbols","I79";
;
HDL_POWER"PVDDQ_KLM"
ROOM"DDR4_CH_C"
BODY_TYPE"PLUMBING"
CDS_LIB"mstr_symbols"
BOM_COST"MEM"
VOLTAGE"1.2V";
"G\NAC"21;
%"TAP"
"6","(-100,2725)","2","mstr_standard","I80";
;
HDL_TAP"TRUE"
BODY_TYPE"PLUMBING"
CDS_LIB"mstr_standard";
"B \NAC \NWC"2;
"S \NAC"
BN"28"104;
%"TAP"
"6","(-100,2775)","2","mstr_standard","I81";
;
HDL_TAP"TRUE"
BODY_TYPE"PLUMBING"
CDS_LIB"mstr_standard";
"B \NAC \NWC"2;
"S \NAC"
BN"29"105;
%"TAP"
"6","(-100,2825)","2","mstr_standard","I82";
;
HDL_TAP"TRUE"
BODY_TYPE"PLUMBING"
CDS_LIB"mstr_standard";
"B \NAC \NWC"2;
"S \NAC"
BN"30"99;
%"TAP"
"6","(-100,2875)","2","mstr_standard","I83";
;
HDL_TAP"TRUE"
BODY_TYPE"PLUMBING"
CDS_LIB"mstr_standard";
"B \NAC \NWC"2;
"S \NAC"
BN"31"100;
%"TAP"
"6","(-100,2925)","2","mstr_standard","I84";
;
HDL_TAP"TRUE"
BODY_TYPE"PLUMBING"
CDS_LIB"mstr_standard";
"B \NAC \NWC"2;
"S \NAC"
BN"32"101;
%"TAP"
"6","(-100,2975)","2","mstr_standard","I85";
;
HDL_TAP"TRUE"
BODY_TYPE"PLUMBING"
CDS_LIB"mstr_standard";
"B \NAC \NWC"2;
"S \NAC"
BN"33"102;
%"TAP"
"6","(-100,3025)","2","mstr_standard","I86";
;
HDL_TAP"TRUE"
BODY_TYPE"PLUMBING"
CDS_LIB"mstr_standard";
"B \NAC \NWC"2;
"S \NAC"
BN"34"103;
%"TAP"
"6","(-100,3075)","2","mstr_standard","I87";
;
HDL_TAP"TRUE"
BODY_TYPE"PLUMBING"
CDS_LIB"mstr_standard";
"B \NAC \NWC"2;
"S \NAC"
BN"35"87;
%"TAP"
"6","(-100,3125)","2","mstr_standard","I88";
;
HDL_TAP"TRUE"
BODY_TYPE"PLUMBING"
CDS_LIB"mstr_standard";
"B \NAC \NWC"2;
"S \NAC"
BN"36"89;
%"TAP"
"6","(-100,3175)","2","mstr_standard","I89";
;
HDL_TAP"TRUE"
BODY_TYPE"PLUMBING"
CDS_LIB"mstr_standard";
"B \NAC \NWC"2;
"S \NAC"
BN"37"90;
%"TAP"
"6","(-100,3225)","2","mstr_standard","I90";
;
HDL_TAP"TRUE"
BODY_TYPE"PLUMBING"
CDS_LIB"mstr_standard";
"B \NAC \NWC"2;
"S \NAC"
BN"38"88;
%"TAP"
"6","(-100,3325)","2","mstr_standard","I91";
;
HDL_TAP"TRUE"
BODY_TYPE"PLUMBING"
CDS_LIB"mstr_standard";
"B \NAC \NWC"2;
"S \NAC"
BN"40"86;
%"TAP"
"6","(-100,3275)","2","mstr_standard","I92";
;
HDL_TAP"TRUE"
BODY_TYPE"PLUMBING"
CDS_LIB"mstr_standard";
"B \NAC \NWC"2;
"S \NAC"
BN"39"91;
%"TAP"
"6","(-100,3425)","2","mstr_standard","I93";
;
HDL_TAP"TRUE"
BODY_TYPE"PLUMBING"
CDS_LIB"mstr_standard";
"B \NAC \NWC"2;
"S \NAC"
BN"42"92;
%"TAP"
"6","(-100,3375)","2","mstr_standard","I94";
;
HDL_TAP"TRUE"
BODY_TYPE"PLUMBING"
CDS_LIB"mstr_standard";
"B \NAC \NWC"2;
"S \NAC"
BN"41"85;
%"TAP"
"6","(-100,3475)","2","mstr_standard","I95";
;
HDL_TAP"TRUE"
BODY_TYPE"PLUMBING"
CDS_LIB"mstr_standard";
"B \NAC \NWC"2;
"S \NAC"
BN"43"93;
%"TAP"
"6","(-100,3575)","2","mstr_standard","I96";
;
HDL_TAP"TRUE"
BODY_TYPE"PLUMBING"
CDS_LIB"mstr_standard";
"B \NAC \NWC"2;
"S \NAC"
BN"45"95;
%"TAP"
"6","(-100,3525)","2","mstr_standard","I97";
;
HDL_TAP"TRUE"
BODY_TYPE"PLUMBING"
CDS_LIB"mstr_standard";
"B \NAC \NWC"2;
"S \NAC"
BN"44"94;
%"TAP"
"6","(-100,3675)","2","mstr_standard","I98";
;
HDL_TAP"TRUE"
BODY_TYPE"PLUMBING"
CDS_LIB"mstr_standard";
"B \NAC \NWC"2;
"S \NAC"
BN"47"75;
%"TAP"
"6","(-100,3625)","2","mstr_standard","I99";
;
HDL_TAP"TRUE"
BODY_TYPE"PLUMBING"
CDS_LIB"mstr_standard";
"B \NAC \NWC"2;
"S \NAC"
BN"46"83;
END.
